(kicad_pcb
	(version 20260206)
	(generator "pcbnew")
	(generator_version "10.0")
	(general
		(thickness 1.6)
		(legacy_teardrops no)
	)
	(paper "A4")
	(title_block
		(title "peb — Lightning_PEB_BRD.brd")
		(comment 1 "Lightning (Wiwynn / Facebook NVMe JBOF) / footprints 732-738 of 2563")
	)
	(layers
		(0 "F.Cu" signal "TOP")
		(4 "In1.Cu" signal "L2GND")
		(6 "In2.Cu" signal "L3")
		(8 "In3.Cu" signal "L4VCC")
		(10 "In4.Cu" signal "L5VCC")
		(12 "In5.Cu" signal "L6")
		(14 "In6.Cu" signal "L7GND")
		(2 "B.Cu" signal "BOTTOM")
		(9 "F.Adhes" user "F.Adhesive")
		(11 "B.Adhes" user "B.Adhesive")
		(13 "F.Paste" user "Package Geometry/Pastemask Top")
		(15 "B.Paste" user "Package Geometry/Pastemask Bottom")
		(5 "F.SilkS" user "Ref Des/Silkscreen Top")
		(7 "B.SilkS" user "Ref Des/Silkscreen Bottom")
		(1 "F.Mask" user "Board Geometry/Soldermask Top")
		(3 "B.Mask" user "Board Geometry/Soldermask Bottom")
		(17 "Dwgs.User" user "User.Drawings")
		(19 "Cmts.User" user "User.Comments")
		(21 "Eco1.User" user "User.Eco1")
		(23 "Eco2.User" user "User.Eco2")
		(25 "Edge.Cuts" user "Board Geometry/Outline")
		(27 "Margin" user)
		(31 "F.CrtYd" user "Package Geometry/Place Bound Top")
		(29 "B.CrtYd" user "Package Geometry/Place Bound Bottom")
		(35 "F.Fab" user "Ref Des/Assembly Top")
		(33 "B.Fab" user "Ref Des/Assembly Bottom")
	)
	(footprint ""
		(layer "F.Cu")
		(at 122.557286 -84.846414 -90)
		(property "Reference" "R5200"
			(at 0 0 270)
			(layer "F.SilkS")
			(hide yes)
			(effects
				(font
					(size 1.27 1.27)
				)
			)
		)
		(property "Value" "0R2J-2-GP"
			(at 0.064008 -3.993896 270)
			(unlocked yes)
			(layer "F.Fab")
			(hide yes)
			(effects
				(font
					(size 1.016 1.016)
					(thickness 0.1524)
				)
			)
		)
		(property "Device Type" "R402H16"
			(at 0.064008 -5.517896 270)
			(unlocked yes)
			(layer "F.Fab")
			(hide yes)
			(effects
				(font
					(size 1.016 1.016)
					(thickness 0.1524)
				)
			)
		)
		(duplicate_pad_numbers_are_jumpers no)
		(fp_line
			(start -0.508 -0.9398)
			(end -0.508 0.9398)
			(stroke
				(width 0.1524)
				(type default)
			)
			(layer "F.SilkS")
		)
		(fp_line
			(start 0.508 -0.9398)
			(end -0.508 -0.9398)
			(stroke
				(width 0.1524)
				(type default)
			)
			(layer "F.SilkS")
		)
		(fp_rect
			(start -0.508 0.9398)
			(end 0.508 -0.9398)
			(stroke
				(width 0)
				(type default)
			)
			(fill no)
			(layer "F.CrtYd")
		)
		(fp_rect
			(start -0.508 0.9398)
			(end 0.508 -0.9398)
			(stroke
				(width 0)
				(type default)
			)
			(fill no)
			(layer "F.Fab")
		)
		(pad "1" smd custom
			(at 0 -0.4445 270)
			(size 0.1397 0.1397)
			(layers "F.Cu" "F.Mask" "F.Paste")
			(net "RTC_I2C_SCL")
			(options
				(clearance outline)
				(anchor circle)
			)
			(primitives
				(gr_poly
					(pts
						(arc
							(start -0.1778 -0.2794)
							(mid -0.249642 -0.249642)
							(end -0.2794 -0.1778)
						)
						(arc
							(start -0.2794 0.1778)
							(mid -0.249642 0.249642)
							(end -0.1778 0.2794)
						)
						(arc
							(start 0.1778 0.2794)
							(mid 0.249642 0.249642)
							(end 0.2794 0.1778)
						)
						(arc
							(start 0.2794 -0.1778)
							(mid 0.249642 -0.249642)
							(end 0.1778 -0.2794)
						)
					)
					(width 0)
					(fill yes)
				)
			)
		)
		(pad "2" smd custom
			(at 0 0.4445 270)
			(size 0.1397 0.1397)
			(layers "F.Cu" "F.Mask" "F.Paste")
			(net "BMC_I2C5_D_PEB_SCL")
			(options
				(clearance outline)
				(anchor circle)
			)
			(primitives
				(gr_poly
					(pts
						(arc
							(start -0.1778 -0.2794)
							(mid -0.249642 -0.249642)
							(end -0.2794 -0.1778)
						)
						(arc
							(start -0.2794 0.1778)
							(mid -0.249642 0.249642)
							(end -0.1778 0.2794)
						)
						(arc
							(start 0.1778 0.2794)
							(mid 0.249642 0.249642)
							(end 0.2794 0.1778)
						)
						(arc
							(start 0.2794 -0.1778)
							(mid 0.249642 -0.249642)
							(end 0.1778 -0.2794)
						)
					)
					(width 0)
					(fill yes)
				)
			)
		)
	)
	(footprint ""
		(layer "F.Cu")
		(at 154.392122 -212.420454 180)
		(property "Reference" "C250"
			(at 0 0 180)
			(layer "F.SilkS")
			(hide yes)
			(effects
				(font
					(size 1.27 1.27)
				)
			)
		)
		(property "Value" "SCD22U10V2KX-1GP"
			(at 1.1811 -2.7051 180)
			(unlocked yes)
			(layer "F.Fab")
			(hide yes)
			(effects
				(font
					(size 1.016 1.016)
					(thickness 0.1524)
				)
			)
		)
		(property "Device Type" "C402H22"
			(at 1.1811 -4.2291 180)
			(unlocked yes)
			(layer "F.Fab")
			(hide yes)
			(effects
				(font
					(size 1.016 1.016)
					(thickness 0.1524)
				)
			)
		)
		(duplicate_pad_numbers_are_jumpers no)
		(fp_rect
			(start -0.4318 0.9525)
			(end 0.4318 -0.9525)
			(stroke
				(width 0)
				(type default)
			)
			(fill no)
			(layer "F.CrtYd")
		)
		(fp_rect
			(start -0.4318 0.9525)
			(end 0.4318 -0.9525)
			(stroke
				(width 0)
				(type default)
			)
			(fill no)
			(layer "F.Fab")
		)
		(pad "1" smd custom
			(at 0 -0.4445 180)
			(size 0.1524 0.1524)
			(layers "F.Cu" "F.Mask" "F.Paste")
			(net "PCIE_TX_CAP_P54")
			(options
				(clearance outline)
				(anchor circle)
			)
			(primitives
				(gr_poly
					(pts
						(arc
							(start 0.3048 -0.2032)
							(mid 0.275042 -0.275042)
							(end 0.2032 -0.3048)
						)
						(arc
							(start -0.2032 -0.3048)
							(mid -0.275042 -0.275042)
							(end -0.3048 -0.2032)
						)
						(arc
							(start -0.3048 0.2032)
							(mid -0.275042 0.275042)
							(end -0.2032 0.3048)
						)
						(arc
							(start 0.2032 0.3048)
							(mid 0.275042 0.275042)
							(end 0.3048 0.2032)
						)
					)
					(width 0)
					(fill yes)
				)
			)
		)
		(pad "2" smd custom
			(at 0 0.4445 180)
			(size 0.1524 0.1524)
			(layers "F.Cu" "F.Mask" "F.Paste")
			(net "PCIE_TX_P54")
			(options
				(clearance outline)
				(anchor circle)
			)
			(primitives
				(gr_poly
					(pts
						(arc
							(start 0.3048 -0.2032)
							(mid 0.275042 -0.275042)
							(end 0.2032 -0.3048)
						)
						(arc
							(start -0.2032 -0.3048)
							(mid -0.275042 -0.275042)
							(end -0.3048 -0.2032)
						)
						(arc
							(start -0.3048 0.2032)
							(mid -0.275042 0.275042)
							(end -0.2032 0.3048)
						)
						(arc
							(start 0.2032 0.3048)
							(mid 0.275042 0.275042)
							(end 0.3048 0.2032)
						)
					)
					(width 0)
					(fill yes)
				)
			)
		)
	)
	(footprint ""
		(layer "F.Cu")
		(at 21.6281 -50.6476 -90)
		(property "Reference" "D17"
			(at 0 0 270)
			(layer "F.SilkS")
			(hide yes)
			(effects
				(font
					(size 1.27 1.27)
				)
			)
		)
		(property "Value" "PGB1010603MR-GP"
			(at -0.0254 -2.8956 270)
			(unlocked yes)
			(layer "F.Fab")
			(hide yes)
			(effects
				(font
					(size 1.016 1.016)
					(thickness 0.1524)
				)
			)
		)
		(property "Device Type" "L1608-UH15"
			(at -0.0254 -4.4196 270)
			(unlocked yes)
			(layer "F.Fab")
			(hide yes)
			(effects
				(font
					(size 1.016 1.016)
					(thickness 0.1524)
				)
			)
		)
		(duplicate_pad_numbers_are_jumpers no)
		(fp_line
			(start 0.254 0)
			(end -0.254 0)
			(stroke
				(width 0.2032)
				(type default)
			)
			(layer "F.SilkS")
		)
		(fp_rect
			(start -0.5842 1.3335)
			(end 0.5842 -1.3335)
			(stroke
				(width 0)
				(type default)
			)
			(fill no)
			(layer "F.CrtYd")
		)
		(fp_rect
			(start -0.5842 1.3335)
			(end 0.5842 -1.3335)
			(stroke
				(width 0)
				(type default)
			)
			(fill no)
			(layer "F.Fab")
		)
		(pad "1" smd custom
			(at 0 -0.762 270)
			(size 0.2159 0.2159)
			(layers "F.Cu" "F.Mask" "F.Paste")
			(net "NIC0_MDI0_N3_R")
			(options
				(clearance outline)
				(anchor circle)
			)
			(primitives
				(gr_poly
					(pts
						(arc
							(start -0.3302 -0.4318)
							(mid -0.402042 -0.402042)
							(end -0.4318 -0.3302)
						)
						(arc
							(start -0.4318 0.3302)
							(mid -0.402042 0.402042)
							(end -0.3302 0.4318)
						)
						(arc
							(start 0.3302 0.4318)
							(mid 0.402042 0.402042)
							(end 0.4318 0.3302)
						)
						(arc
							(start 0.4318 -0.3302)
							(mid 0.402042 -0.402042)
							(end 0.3302 -0.4318)
						)
					)
					(width 0)
					(fill yes)
				)
			)
		)
		(pad "2" smd custom
			(at 0 0.762 270)
			(size 0.2159 0.2159)
			(layers "F.Cu" "F.Mask" "F.Paste")
			(net "GND")
			(options
				(clearance outline)
				(anchor circle)
			)
			(primitives
				(gr_poly
					(pts
						(arc
							(start -0.3302 -0.4318)
							(mid -0.402042 -0.402042)
							(end -0.4318 -0.3302)
						)
						(arc
							(start -0.4318 0.3302)
							(mid -0.402042 0.402042)
							(end -0.3302 0.4318)
						)
						(arc
							(start 0.3302 0.4318)
							(mid 0.402042 0.402042)
							(end 0.4318 0.3302)
						)
						(arc
							(start 0.4318 -0.3302)
							(mid 0.402042 -0.402042)
							(end 0.3302 -0.4318)
						)
					)
					(width 0)
					(fill yes)
				)
			)
		)
	)
	(footprint ""
		(layer "F.Cu")
		(at 218.77274 -31.142432)
		(property "Reference" "TP267"
			(at 0 0 0)
			(layer "F.SilkS")
			(hide yes)
			(effects
				(font
					(size 1.27 1.27)
				)
			)
		)
		(property "Value" "TPAD28-2-GP"
			(at -0.0127 -1.6637 0)
			(unlocked yes)
			(layer "F.Fab")
			(hide yes)
			(effects
				(font
					(size 1.016 1.016)
					(thickness 0.1524)
				)
			)
		)
		(property "Device Type" "TPAD28"
			(at -0.0127 -3.1877 0)
			(unlocked yes)
			(layer "F.Fab")
			(hide yes)
			(effects
				(font
					(size 1.016 1.016)
					(thickness 0.1524)
				)
			)
		)
		(duplicate_pad_numbers_are_jumpers no)
		(fp_poly
			(pts
				(arc
					(start 0.3556 0)
					(mid -0.3556 0)
					(end 0.3556 0)
				)
			)
			(stroke
				(width 0)
				(type default)
			)
			(fill no)
			(layer "F.CrtYd")
		)
		(fp_poly
			(pts
				(arc
					(start 0.6096 0)
					(mid -0.6096 0)
					(end 0.6096 0)
				)
			)
			(stroke
				(width 0)
				(type default)
			)
			(fill no)
			(layer "F.Fab")
		)
		(pad "1" smd circle
			(at 0 0)
			(size 0.7112 0.7112)
			(layers "F.Cu" "F.Mask" "F.Paste")
			(net "LBI_DATA_8")
		)
	)
	(footprint ""
		(layer "F.Cu")
		(at 8.982964 -86.437978 90)
		(property "Reference" "X1"
			(at 0 0 90)
			(layer "F.SilkS")
			(hide yes)
			(effects
				(font
					(size 1.27 1.27)
				)
			)
		)
		(property "Value" "OSC-50MHZ-8-GP-U"
			(at -5.183886 1.282192 90)
			(unlocked yes)
			(layer "F.Fab")
			(hide yes)
			(effects
				(font
					(size 1.016 1.016)
					(thickness 0.1524)
				)
			)
		)
		(property "Device Type" "S-OSC4-7349H75"
			(at -5.183886 -0.241808 90)
			(unlocked yes)
			(layer "F.Fab")
			(hide yes)
			(effects
				(font
					(size 1.016 1.016)
					(thickness 0.1524)
				)
			)
		)
		(duplicate_pad_numbers_are_jumpers no)
		(fp_line
			(start 3.8989 -3.2131)
			(end 3.8989 3.2131)
			(stroke
				(width 0.1524)
				(type default)
			)
			(layer "F.SilkS")
		)
		(fp_line
			(start -3.8989 -3.2131)
			(end 3.8989 -3.2131)
			(stroke
				(width 0.1524)
				(type default)
			)
			(layer "F.SilkS")
		)
		(fp_line
			(start -3.9878 2.0447)
			(end -3.9878 3.3147)
			(stroke
				(width 0.3302)
				(type default)
			)
			(layer "F.SilkS")
		)
		(fp_line
			(start 3.8989 3.2131)
			(end -3.8989 3.2131)
			(stroke
				(width 0.1524)
				(type default)
			)
			(layer "F.SilkS")
		)
		(fp_line
			(start -3.8989 3.2131)
			(end -3.8989 -3.2131)
			(stroke
				(width 0.1524)
				(type default)
			)
			(layer "F.SilkS")
		)
		(fp_line
			(start -3.9878 3.3147)
			(end -2.7178 3.3147)
			(stroke
				(width 0.3302)
				(type default)
			)
			(layer "F.SilkS")
		)
		(fp_poly
			(pts
				(xy -3.175 3.9243) (xy -1.905 3.9243) (xy -2.54 3.2893)
			)
			(stroke
				(width 0)
				(type default)
			)
			(fill yes)
			(layer "F.SilkS")
		)
		(fp_rect
			(start -3.6449 2.4511)
			(end 3.6449 -2.4511)
			(stroke
				(width 0)
				(type default)
			)
			(fill no)
			(layer "F.CrtYd")
		)
		(fp_poly
			(pts
				(xy -4.1529 3.4671) (xy -4.1529 -0.5842) (xy -3.6449 -0.5842) (xy -3.6449 2.4511) (xy 3.6449 2.4511)
				(xy 3.6449 -2.4511) (xy -3.6449 -2.4511) (xy -3.6449 -0.5969) (xy -4.1529 -0.5969) (xy -4.1529 -3.4671)
				(xy 4.1529 -3.4671) (xy 4.1529 3.4671)
			)
			(stroke
				(width 0)
				(type default)
			)
			(fill no)
			(layer "F.CrtYd")
		)
		(fp_rect
			(start -4.1529 3.4671)
			(end 4.1529 -3.4671)
			(stroke
				(width 0)
				(type default)
			)
			(fill no)
			(layer "F.Fab")
		)
		(pad "1" smd rect
			(at -2.54 2.005584 90)
			(size 1.651 1.905)
			(layers "F.Cu" "F.Mask" "F.Paste")
			(net "FM_OSC_50M_EN")
		)
		(pad "2" smd rect
			(at 2.54 2.005584 90)
			(size 1.651 1.905)
			(layers "F.Cu" "F.Mask" "F.Paste")
			(net "GND")
		)
		(pad "3" smd rect
			(at 2.54 -2.005584 90)
			(size 1.651 1.905)
			(layers "F.Cu" "F.Mask" "F.Paste")
			(net "50M_CLK_OUT")
		)
		(pad "4" smd rect
			(at -2.54 -2.005584 90)
			(size 1.651 1.905)
			(layers "F.Cu" "F.Mask" "F.Paste")
			(net "P3V3_STBY")
		)
		(zone
			(layer "F.Cu")
			(hatch none 0.5)
			(connect_pads
				(clearance 0)
			)
			(min_thickness 0.25)
			(keepout
				(tracks not_allowed)
				(vias allowed)
				(pads allowed)
				(copperpour not_allowed)
				(footprints allowed)
			)
			(placement
				(enabled no)
				(sheetname "")
			)
			(fill
				(thermal_gap 0.5)
				(thermal_bridge_width 0.5)
				(island_removal_mode 0)
			)
			(polygon
				(pts
					(xy 9.706864 -85.040978) (xy 8.259064 -85.040978) (xy 8.259064 -87.834978) (xy 9.706864 -87.834978)
				)
			)
		)
		(zone
			(layer "F.Cu")
			(hatch none 0.5)
			(connect_pads
				(clearance 0)
			)
			(min_thickness 0.25)
			(keepout
				(tracks allowed)
				(vias not_allowed)
				(pads allowed)
				(copperpour not_allowed)
				(footprints allowed)
			)
			(placement
				(enabled no)
				(sheetname "")
			)
			(fill
				(thermal_gap 0.5)
				(thermal_bridge_width 0.5)
				(island_removal_mode 0)
			)
			(polygon
				(pts
					(xy 11.941048 -84.723478) (xy 10.036048 -84.723478) (xy 10.036048 -83.072478) (xy 7.92988 -83.072478)
					(xy 7.92988 -84.723478) (xy 6.02488 -84.723478) (xy 6.02488 -88.152478) (xy 7.92988 -88.152478)
					(xy 7.92988 -89.803478) (xy 10.036048 -89.803478) (xy 10.036048 -88.152478) (xy 11.941048 -88.152478)
				)
			)
		)
	)
	(footprint ""
		(layer "F.Cu")
		(at 120.9548 -101.4222 180)
		(property "Reference" "R864"
			(at 0 0 180)
			(layer "F.SilkS")
			(hide yes)
			(effects
				(font
					(size 1.27 1.27)
				)
			)
		)
		(property "Value" "0R2J-2-GP"
			(at 0.064008 -3.993896 180)
			(unlocked yes)
			(layer "F.Fab")
			(hide yes)
			(effects
				(font
					(size 1.016 1.016)
					(thickness 0.1524)
				)
			)
		)
		(property "Device Type" "R402H16"
			(at 0.064008 -5.517896 180)
			(unlocked yes)
			(layer "F.Fab")
			(hide yes)
			(effects
				(font
					(size 1.016 1.016)
					(thickness 0.1524)
				)
			)
		)
		(duplicate_pad_numbers_are_jumpers no)
		(fp_line
			(start 0.508 -0.9398)
			(end -0.508 -0.9398)
			(stroke
				(width 0.1524)
				(type default)
			)
			(layer "F.SilkS")
		)
		(fp_line
			(start -0.508 -0.9398)
			(end -0.508 0.9398)
			(stroke
				(width 0.1524)
				(type default)
			)
			(layer "F.SilkS")
		)
		(fp_rect
			(start -0.508 0.9398)
			(end 0.508 -0.9398)
			(stroke
				(width 0)
				(type default)
			)
			(fill no)
			(layer "F.CrtYd")
		)
		(fp_rect
			(start -0.508 0.9398)
			(end 0.508 -0.9398)
			(stroke
				(width 0)
				(type default)
			)
			(fill no)
			(layer "F.Fab")
		)
		(pad "1" smd custom
			(at 0 -0.4445 180)
			(size 0.1397 0.1397)
			(layers "F.Cu" "F.Mask" "F.Paste")
			(net "BUF_I2C_SDA_2_R")
			(options
				(clearance outline)
				(anchor circle)
			)
			(primitives
				(gr_poly
					(pts
						(arc
							(start -0.1778 -0.2794)
							(mid -0.249642 -0.249642)
							(end -0.2794 -0.1778)
						)
						(arc
							(start -0.2794 0.1778)
							(mid -0.249642 0.249642)
							(end -0.1778 0.2794)
						)
						(arc
							(start 0.1778 0.2794)
							(mid 0.249642 0.249642)
							(end 0.2794 0.1778)
						)
						(arc
							(start 0.2794 -0.1778)
							(mid 0.249642 -0.249642)
							(end 0.1778 -0.2794)
						)
					)
					(width 0)
					(fill yes)
				)
			)
		)
		(pad "2" smd custom
			(at 0 0.4445 180)
			(size 0.1397 0.1397)
			(layers "F.Cu" "F.Mask" "F.Paste")
			(net "TWI_SDA0")
			(options
				(clearance outline)
				(anchor circle)
			)
			(primitives
				(gr_poly
					(pts
						(arc
							(start -0.1778 -0.2794)
							(mid -0.249642 -0.249642)
							(end -0.2794 -0.1778)
						)
						(arc
							(start -0.2794 0.1778)
							(mid -0.249642 0.249642)
							(end -0.1778 0.2794)
						)
						(arc
							(start 0.1778 0.2794)
							(mid 0.249642 0.249642)
							(end 0.2794 0.1778)
						)
						(arc
							(start 0.2794 -0.1778)
							(mid 0.249642 -0.249642)
							(end 0.1778 -0.2794)
						)
					)
					(width 0)
					(fill yes)
				)
			)
		)
	)
	(footprint ""
		(layer "F.Cu")
		(at 275.599906 -17.500092 90)
		(property "Reference" "LED23"
			(at 0 0 90)
			(layer "F.SilkS")
			(hide yes)
			(effects
				(font
					(size 1.27 1.27)
				)
			)
		)
		(property "Value" "LED-YG-51-GP"
			(at -2.6924 -1.4224 90)
			(unlocked yes)
			(layer "F.Fab")
			(hide yes)
			(effects
				(font
					(size 1.016 1.016)
					(thickness 0.1524)
				)
			)
		)
		(property "Device Type" "LED1608AKH40"
			(at -2.6924 -2.9464 90)
			(unlocked yes)
			(layer "F.Fab")
			(hide yes)
			(effects
				(font
					(size 1.016 1.016)
					(thickness 0.1524)
				)
			)
		)
		(duplicate_pad_numbers_are_jumpers no)
		(fp_line
			(start 0.6604 -1.3716)
			(end 0.6604 1.3716)
			(stroke
				(width 0.1524)
				(type default)
			)
			(layer "F.SilkS")
		)
		(fp_line
			(start -0.6604 -1.3716)
			(end 0.6604 -1.3716)
			(stroke
				(width 0.1524)
				(type default)
			)
			(layer "F.SilkS")
		)
		(fp_line
			(start 0.6604 1.3716)
			(end -0.6604 1.3716)
			(stroke
				(width 0.1524)
				(type default)
			)
			(layer "F.SilkS")
		)
		(fp_line
			(start -0.6604 1.3716)
			(end -0.6604 -1.3716)
			(stroke
				(width 0.1524)
				(type default)
			)
			(layer "F.SilkS")
		)
		(fp_line
			(start -0.5969 1.5494)
			(end 0.5842 1.5494)
			(stroke
				(width 0.508)
				(type default)
			)
			(layer "F.SilkS")
		)
		(fp_line
			(start 0.7493 1.651)
			(end 0.7493 1.1811)
			(stroke
				(width 0.3302)
				(type default)
			)
			(layer "F.SilkS")
		)
		(fp_line
			(start -0.7493 1.651)
			(end -0.7493 1.1811)
			(stroke
				(width 0.3302)
				(type default)
			)
			(layer "F.SilkS")
		)
		(fp_rect
			(start -0.6223 1.3335)
			(end 0.6223 -1.3335)
			(stroke
				(width 0)
				(type default)
			)
			(fill no)
			(layer "F.CrtYd")
		)
		(fp_rect
			(start -0.6223 1.3335)
			(end 0.6223 -1.3335)
			(stroke
				(width 0)
				(type default)
			)
			(fill no)
			(layer "F.Fab")
		)
		(pad "A" smd custom
			(at 0 -0.762 90)
			(size 0.2159 0.2159)
			(layers "F.Cu" "F.Mask" "F.Paste")
			(net "LED_R_14")
			(options
				(clearance outline)
				(anchor circle)
			)
			(primitives
				(gr_poly
					(pts
						(arc
							(start -0.3302 -0.4318)
							(mid -0.402042 -0.402042)
							(end -0.4318 -0.3302)
						)
						(arc
							(start -0.4318 0.3302)
							(mid -0.402042 0.402042)
							(end -0.3302 0.4318)
						)
						(arc
							(start 0.3302 0.4318)
							(mid 0.402042 0.402042)
							(end 0.4318 0.3302)
						)
						(arc
							(start 0.4318 -0.3302)
							(mid 0.402042 -0.402042)
							(end 0.3302 -0.4318)
						)
					)
					(width 0)
					(fill yes)
				)
			)
		)
		(pad "K" smd custom
			(at 0 0.762 90)
			(size 0.2159 0.2159)
			(layers "F.Cu" "F.Mask" "F.Paste")
			(net "LED_Q_14")
			(options
				(clearance outline)
				(anchor circle)
			)
			(primitives
				(gr_poly
					(pts
						(arc
							(start -0.3302 -0.4318)
							(mid -0.402042 -0.402042)
							(end -0.4318 -0.3302)
						)
						(arc
							(start -0.4318 0.3302)
							(mid -0.402042 0.402042)
							(end -0.3302 0.4318)
						)
						(arc
							(start 0.3302 0.4318)
							(mid 0.402042 0.402042)
							(end 0.4318 0.3302)
						)
						(arc
							(start 0.4318 -0.3302)
							(mid 0.402042 -0.402042)
							(end 0.3302 -0.4318)
						)
					)
					(width 0)
					(fill yes)
				)
			)
		)
	)
)
